(kicad_pcb
	(version 20260206)
	(generator "pcbnew")
	(generator_version "10.0")
	(general
		(thickness 1.6)
		(legacy_teardrops no)
	)
	(paper "A4")
	(title_block
		(title "peb — Lightning_PEB_BRD.brd")
		(comment 1 "Lightning (Wiwynn / Facebook NVMe JBOF) / footprints 2529-2535 of 2563")
	)
	(layers
		(0 "F.Cu" signal "TOP")
		(4 "In1.Cu" signal "L2GND")
		(6 "In2.Cu" signal "L3")
		(8 "In3.Cu" signal "L4VCC")
		(10 "In4.Cu" signal "L5VCC")
		(12 "In5.Cu" signal "L6")
		(14 "In6.Cu" signal "L7GND")
		(2 "B.Cu" signal "BOTTOM")
		(9 "F.Adhes" user "F.Adhesive")
		(11 "B.Adhes" user "B.Adhesive")
		(13 "F.Paste" user "Package Geometry/Pastemask Top")
		(15 "B.Paste" user "Package Geometry/Pastemask Bottom")
		(5 "F.SilkS" user "Ref Des/Silkscreen Top")
		(7 "B.SilkS" user "Ref Des/Silkscreen Bottom")
		(1 "F.Mask" user "Board Geometry/Soldermask Top")
		(3 "B.Mask" user "Board Geometry/Soldermask Bottom")
		(17 "Dwgs.User" user "User.Drawings")
		(19 "Cmts.User" user "User.Comments")
		(21 "Eco1.User" user "User.Eco1")
		(23 "Eco2.User" user "User.Eco2")
		(25 "Edge.Cuts" user "Board Geometry/Outline")
		(27 "Margin" user)
		(31 "F.CrtYd" user "Package Geometry/Place Bound Top")
		(29 "B.CrtYd" user "Package Geometry/Place Bound Bottom")
		(35 "F.Fab" user "Ref Des/Assembly Top")
		(33 "B.Fab" user "Ref Des/Assembly Bottom")
	)
	(footprint ""
		(layer "B.Cu")
		(at 314.276232 -37.732462 180)
		(property "Reference" "C278"
			(at 0 0 0)
			(layer "B.SilkS")
			(hide yes)
			(effects
				(font
					(size 1.27 1.27)
				)
				(justify mirror)
			)
		)
		(property "Value" "SCD1U10V2KX-5GP"
			(at -1.1811 -2.7051 180)
			(unlocked yes)
			(layer "B.Fab")
			(hide yes)
			(effects
				(font
					(size 1.016 1.016)
					(thickness 0.1524)
				)
				(justify mirror)
			)
		)
		(property "Device Type" "C402H22"
			(at -1.1811 -4.2291 180)
			(unlocked yes)
			(layer "B.Fab")
			(hide yes)
			(effects
				(font
					(size 1.016 1.016)
					(thickness 0.1524)
				)
				(justify mirror)
			)
		)
		(duplicate_pad_numbers_are_jumpers no)
		(fp_rect
			(start 0.4318 0.9525)
			(end -0.4318 -0.9525)
			(stroke
				(width 0)
				(type default)
			)
			(fill no)
			(layer "B.CrtYd")
		)
		(fp_rect
			(start 0.4318 0.9525)
			(end -0.4318 -0.9525)
			(stroke
				(width 0)
				(type default)
			)
			(fill no)
			(layer "B.Fab")
		)
		(pad "1" smd custom
			(at 0 -0.4445)
			(size 0.1524 0.1524)
			(layers "B.Cu" "B.Mask" "B.Paste")
			(net "GND")
			(options
				(clearance outline)
				(anchor circle)
			)
			(primitives
				(gr_poly
					(pts
						(arc
							(start 0.3048 0.2032)
							(mid 0.275042 0.275042)
							(end 0.2032 0.3048)
						)
						(arc
							(start -0.2032 0.3048)
							(mid -0.275042 0.275042)
							(end -0.3048 0.2032)
						)
						(arc
							(start -0.3048 -0.2032)
							(mid -0.275042 -0.275042)
							(end -0.2032 -0.3048)
						)
						(arc
							(start 0.2032 -0.3048)
							(mid 0.275042 -0.275042)
							(end 0.3048 -0.2032)
						)
					)
					(width 0)
					(fill yes)
				)
			)
		)
		(pad "2" smd custom
			(at 0 0.4445)
			(size 0.1524 0.1524)
			(layers "B.Cu" "B.Mask" "B.Paste")
			(net "P3V3_STBY")
			(options
				(clearance outline)
				(anchor circle)
			)
			(primitives
				(gr_poly
					(pts
						(arc
							(start 0.3048 0.2032)
							(mid 0.275042 0.275042)
							(end 0.2032 0.3048)
						)
						(arc
							(start -0.2032 0.3048)
							(mid -0.275042 0.275042)
							(end -0.3048 0.2032)
						)
						(arc
							(start -0.3048 -0.2032)
							(mid -0.275042 -0.275042)
							(end -0.2032 -0.3048)
						)
						(arc
							(start 0.2032 -0.3048)
							(mid 0.275042 -0.275042)
							(end 0.3048 -0.2032)
						)
					)
					(width 0)
					(fill yes)
				)
			)
		)
	)
	(footprint ""
		(layer "B.Cu")
		(at 42.4942 -187.4012 180)
		(property "Reference" "R869"
			(at 0 0 0)
			(layer "B.SilkS")
			(hide yes)
			(effects
				(font
					(size 1.27 1.27)
				)
				(justify mirror)
			)
		)
		(property "Value" "0R2J-2-GP"
			(at -0.064008 -3.993896 180)
			(unlocked yes)
			(layer "B.Fab")
			(hide yes)
			(effects
				(font
					(size 1.016 1.016)
					(thickness 0.1524)
				)
				(justify mirror)
			)
		)
		(property "Device Type" "R402H16"
			(at -0.064008 -5.517896 180)
			(unlocked yes)
			(layer "B.Fab")
			(hide yes)
			(effects
				(font
					(size 1.016 1.016)
					(thickness 0.1524)
				)
				(justify mirror)
			)
		)
		(duplicate_pad_numbers_are_jumpers no)
		(fp_line
			(start 0.508 -0.9398)
			(end 0.508 0.9398)
			(stroke
				(width 0.1524)
				(type default)
			)
			(layer "B.SilkS")
		)
		(fp_line
			(start -0.508 -0.9398)
			(end 0.508 -0.9398)
			(stroke
				(width 0.1524)
				(type default)
			)
			(layer "B.SilkS")
		)
		(fp_rect
			(start 0.508 0.9398)
			(end -0.508 -0.9398)
			(stroke
				(width 0)
				(type default)
			)
			(fill no)
			(layer "B.CrtYd")
		)
		(fp_rect
			(start 0.508 0.9398)
			(end -0.508 -0.9398)
			(stroke
				(width 0)
				(type default)
			)
			(fill no)
			(layer "B.Fab")
		)
		(pad "1" smd custom
			(at 0 -0.4445)
			(size 0.1397 0.1397)
			(layers "B.Cu" "B.Mask" "B.Paste")
			(net "BMC_I2C9_CLKBUF2_SDA")
			(options
				(clearance outline)
				(anchor circle)
			)
			(primitives
				(gr_poly
					(pts
						(arc
							(start -0.1778 0.2794)
							(mid -0.249642 0.249642)
							(end -0.2794 0.1778)
						)
						(arc
							(start -0.2794 -0.1778)
							(mid -0.249642 -0.249642)
							(end -0.1778 -0.2794)
						)
						(arc
							(start 0.1778 -0.2794)
							(mid 0.249642 -0.249642)
							(end 0.2794 -0.1778)
						)
						(arc
							(start 0.2794 0.1778)
							(mid 0.249642 0.249642)
							(end 0.1778 0.2794)
						)
					)
					(width 0)
					(fill yes)
				)
			)
		)
		(pad "2" smd custom
			(at 0 0.4445)
			(size 0.1397 0.1397)
			(layers "B.Cu" "B.Mask" "B.Paste")
			(net "BUF_I2C9_CLKBUF2_SDA")
			(options
				(clearance outline)
				(anchor circle)
			)
			(primitives
				(gr_poly
					(pts
						(arc
							(start -0.1778 0.2794)
							(mid -0.249642 0.249642)
							(end -0.2794 0.1778)
						)
						(arc
							(start -0.2794 -0.1778)
							(mid -0.249642 -0.249642)
							(end -0.1778 -0.2794)
						)
						(arc
							(start 0.1778 -0.2794)
							(mid 0.249642 -0.249642)
							(end 0.2794 -0.1778)
						)
						(arc
							(start 0.2794 0.1778)
							(mid 0.249642 0.249642)
							(end 0.1778 0.2794)
						)
					)
					(width 0)
					(fill yes)
				)
			)
		)
	)
	(footprint ""
		(layer "B.Cu")
		(at 271.018 -6.223 90)
		(property "Reference" "R2965"
			(at 0 0 90)
			(layer "B.SilkS")
			(hide yes)
			(effects
				(font
					(size 1.27 1.27)
				)
				(justify mirror)
			)
		)
		(property "Value" "0R2J-2-GP"
			(at -0.064008 -3.993896 90)
			(unlocked yes)
			(layer "B.Fab")
			(hide yes)
			(effects
				(font
					(size 1.016 1.016)
					(thickness 0.1524)
				)
				(justify mirror)
			)
		)
		(property "Device Type" "R402H16"
			(at -0.064008 -5.517896 90)
			(unlocked yes)
			(layer "B.Fab")
			(hide yes)
			(effects
				(font
					(size 1.016 1.016)
					(thickness 0.1524)
				)
				(justify mirror)
			)
		)
		(duplicate_pad_numbers_are_jumpers no)
		(fp_line
			(start 0.508 -0.9398)
			(end 0.508 0.9398)
			(stroke
				(width 0.1524)
				(type default)
			)
			(layer "B.SilkS")
		)
		(fp_line
			(start -0.508 -0.9398)
			(end 0.508 -0.9398)
			(stroke
				(width 0.1524)
				(type default)
			)
			(layer "B.SilkS")
		)
		(fp_rect
			(start 0.508 0.9398)
			(end -0.508 -0.9398)
			(stroke
				(width 0)
				(type default)
			)
			(fill no)
			(layer "B.CrtYd")
		)
		(fp_rect
			(start 0.508 0.9398)
			(end -0.508 -0.9398)
			(stroke
				(width 0)
				(type default)
			)
			(fill no)
			(layer "B.Fab")
		)
		(pad "1" smd custom
			(at 0 -0.4445 270)
			(size 0.1397 0.1397)
			(layers "B.Cu" "B.Mask" "B.Paste")
			(net "PCIE_REFCLK_H1_P")
			(options
				(clearance outline)
				(anchor circle)
			)
			(primitives
				(gr_poly
					(pts
						(arc
							(start -0.1778 0.2794)
							(mid -0.249642 0.249642)
							(end -0.2794 0.1778)
						)
						(arc
							(start -0.2794 -0.1778)
							(mid -0.249642 -0.249642)
							(end -0.1778 -0.2794)
						)
						(arc
							(start 0.1778 -0.2794)
							(mid 0.249642 -0.249642)
							(end 0.2794 -0.1778)
						)
						(arc
							(start 0.2794 0.1778)
							(mid 0.249642 0.249642)
							(end 0.1778 0.2794)
						)
					)
					(width 0)
					(fill yes)
				)
			)
		)
		(pad "2" smd custom
			(at 0 0.4445 270)
			(size 0.1397 0.1397)
			(layers "B.Cu" "B.Mask" "B.Paste")
			(net "PCIE_REFCLK_H1_P_R")
			(options
				(clearance outline)
				(anchor circle)
			)
			(primitives
				(gr_poly
					(pts
						(arc
							(start -0.1778 0.2794)
							(mid -0.249642 0.249642)
							(end -0.2794 0.1778)
						)
						(arc
							(start -0.2794 -0.1778)
							(mid -0.249642 -0.249642)
							(end -0.1778 -0.2794)
						)
						(arc
							(start 0.1778 -0.2794)
							(mid 0.249642 -0.249642)
							(end 0.2794 -0.1778)
						)
						(arc
							(start 0.2794 0.1778)
							(mid 0.249642 0.249642)
							(end 0.1778 0.2794)
						)
					)
					(width 0)
					(fill yes)
				)
			)
		)
	)
	(footprint ""
		(layer "B.Cu")
		(at 245.1481 -40.9956 90)
		(property "Reference" "C484"
			(at 0 0 90)
			(layer "B.SilkS")
			(hide yes)
			(effects
				(font
					(size 1.27 1.27)
				)
				(justify mirror)
			)
		)
		(property "Value" "SCD1U16V1KX-1-GP"
			(at 2.8321 -1.7399 90)
			(unlocked yes)
			(layer "B.Fab")
			(hide yes)
			(effects
				(font
					(size 1.016 1.016)
					(thickness 0.1524)
				)
				(justify mirror)
			)
		)
		(property "Device Type" "C0201H13"
			(at 2.8321 -3.2639 90)
			(unlocked yes)
			(layer "B.Fab")
			(hide yes)
			(effects
				(font
					(size 1.016 1.016)
					(thickness 0.1524)
				)
				(justify mirror)
			)
		)
		(duplicate_pad_numbers_are_jumpers no)
		(fp_rect
			(start 0.2794 0.6477)
			(end -0.2794 -0.6477)
			(stroke
				(width 0)
				(type default)
			)
			(fill no)
			(layer "B.CrtYd")
		)
		(fp_rect
			(start 0.2794 0.6477)
			(end -0.2794 -0.6477)
			(stroke
				(width 0)
				(type default)
			)
			(fill no)
			(layer "B.Fab")
		)
		(pad "1" smd custom
			(at 0 -0.2794 270)
			(size 0.0762 0.0762)
			(layers "B.Cu" "B.Mask" "B.Paste")
			(net "DUT_VDDO")
			(options
				(clearance outline)
				(anchor circle)
			)
			(primitives
				(gr_poly
					(pts
						(arc
							(start 0.1524 0.127)
							(mid 0.137521 0.162921)
							(end 0.1016 0.1778)
						)
						(arc
							(start -0.1016 0.1778)
							(mid -0.137521 0.162921)
							(end -0.1524 0.127)
						)
						(arc
							(start -0.1524 -0.127)
							(mid -0.137521 -0.162921)
							(end -0.1016 -0.1778)
						)
						(arc
							(start 0.1016 -0.1778)
							(mid 0.137521 -0.162921)
							(end 0.1524 -0.127)
						)
					)
					(width 0)
					(fill yes)
				)
			)
		)
		(pad "2" smd custom
			(at 0 0.2794 270)
			(size 0.0762 0.0762)
			(layers "B.Cu" "B.Mask" "B.Paste")
			(net "GND")
			(options
				(clearance outline)
				(anchor circle)
			)
			(primitives
				(gr_poly
					(pts
						(arc
							(start 0.1524 0.127)
							(mid 0.137521 0.162921)
							(end 0.1016 0.1778)
						)
						(arc
							(start -0.1016 0.1778)
							(mid -0.137521 0.162921)
							(end -0.1524 0.127)
						)
						(arc
							(start -0.1524 -0.127)
							(mid -0.137521 -0.162921)
							(end -0.1016 -0.1778)
						)
						(arc
							(start 0.1016 -0.1778)
							(mid 0.137521 -0.162921)
							(end 0.1524 -0.127)
						)
					)
					(width 0)
					(fill yes)
				)
			)
		)
	)
	(footprint ""
		(layer "B.Cu")
		(at 24.13 -122.0216 -90)
		(property "Reference" "R221"
			(at 0 0 90)
			(layer "B.SilkS")
			(hide yes)
			(effects
				(font
					(size 1.27 1.27)
				)
				(justify mirror)
			)
		)
		(property "Value" "4K7R2F-GP"
			(at -0.064008 -3.993896 270)
			(unlocked yes)
			(layer "B.Fab")
			(hide yes)
			(effects
				(font
					(size 1.016 1.016)
					(thickness 0.1524)
				)
				(justify mirror)
			)
		)
		(property "Device Type" "R402H16"
			(at -0.064008 -5.517896 270)
			(unlocked yes)
			(layer "B.Fab")
			(hide yes)
			(effects
				(font
					(size 1.016 1.016)
					(thickness 0.1524)
				)
				(justify mirror)
			)
		)
		(duplicate_pad_numbers_are_jumpers no)
		(fp_line
			(start -0.508 -0.9398)
			(end 0.508 -0.9398)
			(stroke
				(width 0.1524)
				(type default)
			)
			(layer "B.SilkS")
		)
		(fp_line
			(start 0.508 -0.9398)
			(end 0.508 0.9398)
			(stroke
				(width 0.1524)
				(type default)
			)
			(layer "B.SilkS")
		)
		(fp_rect
			(start 0.508 0.9398)
			(end -0.508 -0.9398)
			(stroke
				(width 0)
				(type default)
			)
			(fill no)
			(layer "B.CrtYd")
		)
		(fp_rect
			(start 0.508 0.9398)
			(end -0.508 -0.9398)
			(stroke
				(width 0)
				(type default)
			)
			(fill no)
			(layer "B.Fab")
		)
		(pad "1" smd custom
			(at 0 -0.4445 90)
			(size 0.1397 0.1397)
			(layers "B.Cu" "B.Mask" "B.Paste")
			(net "FCB_HW_REVISION")
			(options
				(clearance outline)
				(anchor circle)
			)
			(primitives
				(gr_poly
					(pts
						(arc
							(start -0.1778 0.2794)
							(mid -0.249642 0.249642)
							(end -0.2794 0.1778)
						)
						(arc
							(start -0.2794 -0.1778)
							(mid -0.249642 -0.249642)
							(end -0.1778 -0.2794)
						)
						(arc
							(start 0.1778 -0.2794)
							(mid 0.249642 -0.249642)
							(end 0.2794 -0.1778)
						)
						(arc
							(start 0.2794 0.1778)
							(mid 0.249642 0.249642)
							(end 0.1778 0.2794)
						)
					)
					(width 0)
					(fill yes)
				)
			)
		)
		(pad "2" smd custom
			(at 0 0.4445 90)
			(size 0.1397 0.1397)
			(layers "B.Cu" "B.Mask" "B.Paste")
			(net "P3V3_STBY")
			(options
				(clearance outline)
				(anchor circle)
			)
			(primitives
				(gr_poly
					(pts
						(arc
							(start -0.1778 0.2794)
							(mid -0.249642 0.249642)
							(end -0.2794 0.1778)
						)
						(arc
							(start -0.2794 -0.1778)
							(mid -0.249642 -0.249642)
							(end -0.1778 -0.2794)
						)
						(arc
							(start 0.1778 -0.2794)
							(mid 0.249642 -0.249642)
							(end 0.2794 -0.1778)
						)
						(arc
							(start 0.2794 0.1778)
							(mid 0.249642 0.249642)
							(end 0.1778 0.2794)
						)
					)
					(width 0)
					(fill yes)
				)
			)
		)
	)
	(footprint ""
		(layer "B.Cu")
		(at 26.797 -73.533)
		(property "Reference" "PR9008"
			(at 0 0 0)
			(layer "B.SilkS")
			(hide yes)
			(effects
				(font
					(size 1.27 1.27)
				)
				(justify mirror)
			)
		)
		(property "Value" "0R2J-2-GP"
			(at -0.064008 -3.993896 0)
			(unlocked yes)
			(layer "B.Fab")
			(hide yes)
			(effects
				(font
					(size 1.016 1.016)
					(thickness 0.1524)
				)
				(justify mirror)
			)
		)
		(property "Device Type" "R402H16"
			(at -0.064008 -5.517896 0)
			(unlocked yes)
			(layer "B.Fab")
			(hide yes)
			(effects
				(font
					(size 1.016 1.016)
					(thickness 0.1524)
				)
				(justify mirror)
			)
		)
		(duplicate_pad_numbers_are_jumpers no)
		(fp_line
			(start -0.508 -0.9398)
			(end 0.508 -0.9398)
			(stroke
				(width 0.1524)
				(type default)
			)
			(layer "B.SilkS")
		)
		(fp_line
			(start 0.508 -0.9398)
			(end 0.508 0.9398)
			(stroke
				(width 0.1524)
				(type default)
			)
			(layer "B.SilkS")
		)
		(fp_rect
			(start 0.508 0.9398)
			(end -0.508 -0.9398)
			(stroke
				(width 0)
				(type default)
			)
			(fill no)
			(layer "B.CrtYd")
		)
		(fp_rect
			(start 0.508 0.9398)
			(end -0.508 -0.9398)
			(stroke
				(width 0)
				(type default)
			)
			(fill no)
			(layer "B.Fab")
		)
		(pad "1" smd custom
			(at 0 -0.4445 180)
			(size 0.1397 0.1397)
			(layers "B.Cu" "B.Mask" "B.Paste")
			(net "MB0_P12V_PWRGOOD")
			(options
				(clearance outline)
				(anchor circle)
			)
			(primitives
				(gr_poly
					(pts
						(arc
							(start -0.1778 0.2794)
							(mid -0.249642 0.249642)
							(end -0.2794 0.1778)
						)
						(arc
							(start -0.2794 -0.1778)
							(mid -0.249642 -0.249642)
							(end -0.1778 -0.2794)
						)
						(arc
							(start 0.1778 -0.2794)
							(mid 0.249642 -0.249642)
							(end 0.2794 -0.1778)
						)
						(arc
							(start 0.2794 0.1778)
							(mid 0.249642 0.249642)
							(end 0.1778 0.2794)
						)
					)
					(width 0)
					(fill yes)
				)
			)
		)
		(pad "2" smd custom
			(at 0 0.4445 180)
			(size 0.1397 0.1397)
			(layers "B.Cu" "B.Mask" "B.Paste")
			(net "P5V_STBY_EN")
			(options
				(clearance outline)
				(anchor circle)
			)
			(primitives
				(gr_poly
					(pts
						(arc
							(start -0.1778 0.2794)
							(mid -0.249642 0.249642)
							(end -0.2794 0.1778)
						)
						(arc
							(start -0.2794 -0.1778)
							(mid -0.249642 -0.249642)
							(end -0.1778 -0.2794)
						)
						(arc
							(start 0.1778 -0.2794)
							(mid 0.249642 -0.249642)
							(end 0.2794 -0.1778)
						)
						(arc
							(start 0.2794 0.1778)
							(mid 0.249642 0.249642)
							(end 0.1778 0.2794)
						)
					)
					(width 0)
					(fill yes)
				)
			)
		)
	)
	(footprint ""
		(layer "B.Cu")
		(at 13.6144 -126.365 180)
		(property "Reference" "R524"
			(at 0 0 0)
			(layer "B.SilkS")
			(hide yes)
			(effects
				(font
					(size 1.27 1.27)
				)
				(justify mirror)
			)
		)
		(property "Value" "4K7R2F-GP"
			(at -0.064008 -3.993896 180)
			(unlocked yes)
			(layer "B.Fab")
			(hide yes)
			(effects
				(font
					(size 1.016 1.016)
					(thickness 0.1524)
				)
				(justify mirror)
			)
		)
		(property "Device Type" "R402H16"
			(at -0.064008 -5.517896 180)
			(unlocked yes)
			(layer "B.Fab")
			(hide yes)
			(effects
				(font
					(size 1.016 1.016)
					(thickness 0.1524)
				)
				(justify mirror)
			)
		)
		(duplicate_pad_numbers_are_jumpers no)
		(fp_line
			(start 0.508 -0.9398)
			(end 0.508 0.9398)
			(stroke
				(width 0.1524)
				(type default)
			)
			(layer "B.SilkS")
		)
		(fp_line
			(start -0.508 -0.9398)
			(end 0.508 -0.9398)
			(stroke
				(width 0.1524)
				(type default)
			)
			(layer "B.SilkS")
		)
		(fp_rect
			(start 0.508 0.9398)
			(end -0.508 -0.9398)
			(stroke
				(width 0)
				(type default)
			)
			(fill no)
			(layer "B.CrtYd")
		)
		(fp_rect
			(start 0.508 0.9398)
			(end -0.508 -0.9398)
			(stroke
				(width 0)
				(type default)
			)
			(fill no)
			(layer "B.Fab")
		)
		(pad "1" smd custom
			(at 0 -0.4445)
			(size 0.1397 0.1397)
			(layers "B.Cu" "B.Mask" "B.Paste")
			(net "BMC_I2C2_MINI2_SCL_S")
			(options
				(clearance outline)
				(anchor circle)
			)
			(primitives
				(gr_poly
					(pts
						(arc
							(start -0.1778 0.2794)
							(mid -0.249642 0.249642)
							(end -0.2794 0.1778)
						)
						(arc
							(start -0.2794 -0.1778)
							(mid -0.249642 -0.249642)
							(end -0.1778 -0.2794)
						)
						(arc
							(start 0.1778 -0.2794)
							(mid 0.249642 -0.249642)
							(end 0.2794 -0.1778)
						)
						(arc
							(start 0.2794 0.1778)
							(mid 0.249642 0.249642)
							(end 0.1778 0.2794)
						)
					)
					(width 0)
					(fill yes)
				)
			)
		)
		(pad "2" smd custom
			(at 0 0.4445)
			(size 0.1397 0.1397)
			(layers "B.Cu" "B.Mask" "B.Paste")
			(net "P3V3_STBY")
			(options
				(clearance outline)
				(anchor circle)
			)
			(primitives
				(gr_poly
					(pts
						(arc
							(start -0.1778 0.2794)
							(mid -0.249642 0.249642)
							(end -0.2794 0.1778)
						)
						(arc
							(start -0.2794 -0.1778)
							(mid -0.249642 -0.249642)
							(end -0.1778 -0.2794)
						)
						(arc
							(start 0.1778 -0.2794)
							(mid 0.249642 -0.249642)
							(end 0.2794 -0.1778)
						)
						(arc
							(start 0.2794 0.1778)
							(mid 0.249642 0.249642)
							(end 0.1778 0.2794)
						)
					)
					(width 0)
					(fill yes)
				)
			)
		)
	)
)
